# Lightning_PEB_EQL.xlsx — Retimerlength (si-constraints)
| 15702-1.1026WPH1646.brd |  |  |  |
| Date Wed Nov 02 17:04:06 2016 |  |  |  |
| Net Name | Etch Length (mils) | Manhattan Length (mils) | Percent Manhattan (mils) |
| 5MIL_DIAG_LED_1X16 | 51.04 | 52.5 | 97.21 |
| 5MIL_DIAG_LED_1X16_D | 2229.5700000000002 | 1997.5 | 111.62 |
| 5MIL_DIAG_LED_2X8 | 49.04 | 50.5 | 97.1 |
| 5MIL_DIAG_LED_2X8_D | 2327.94 | 2232.5 | 104.28 |
| 5MIL_DIAG_LED_4X4 | 47.04 | 48.5 | 96.98 |
| 5MIL_DIAG_LED_4X4_D | 1995.77 | 1951.5 | 102.27 |
| 5MIL_PWR_STATUS_LED | 5718.49 | 5692 | 100.47 |
| 5MIL_PWR_STATUS_LED_D | 5691.46 | 5542.5 | 102.69 |
| 5MIL_PWR_STATUS_LED_EN | 692.02 | 668.25 | 103.56 |
| 5MIL_RITIMER_PCIE_CONFIG_1X16 | 62.61 | 71.25 | 87.87 |
| 5MIL_RITIMER_PCIE_CONFIG_2X8 | 145.07 | 102.25 | 141.88 |
| 5MIL_RITIMER_PCIE_CONFIG_4X4 | 426.94 | 286.75 | 148.88999999999999 |
| AGND_P1V0 | 445.53 | 359.25 | 124.02 |
| AGND_P1V8 | 496.7 | 392.11 | 126.67 |
| AGND_P1V0_A | 468.49 | 409.06 | 114.53 |
| D85_100M_CLKBUFF_LIGHT_R_DN0 | 209.39 | 202.88 | 103.21 |
| D85_100M_CLKBUFF_LIGHT_R_DN1 | 176.57 | 191.13 | 92.38 |
| D85_100M_CLKBUFF_LIGHT_R_DN2 | 344.61 | 399.13 | 86.34 |
| D85_100M_CLKBUFF_LIGHT_R_DN3 | 271.39 | 249.38 | 108.83 |
| D85_100M_CLKBUFF_LIGHT_R_DP0 | 208.89 | 228.13 | 91.57 |
| D85_100M_CLKBUFF_LIGHT_R_DP1 | 176.44 | 166.88 | 105.73 |
| D85_100M_CLKBUFF_LIGHT_R_DP2 | 344.05 | 425.38 | 80.88 |
| D85_100M_CLKBUFF_LIGHT_R_DP3 | 273.95999999999998 | 306.13 | 89.49 |
| D85_100M_CLKBUFF_MINI_DN0_R | 1619.24 | 1436.41 | 112.73 |
| D85_100M_CLKBUFF_MINI_DN1_R | 2159.5700000000002 | 1530.32 | 141.12 |
| D85_100M_CLKBUFF_MINI_DN2_R | 2526.37 | 2051.39 | 123.15 |
| D85_100M_CLKBUFF_MINI_DN3_R | 3322.2 | 2778.46 | 119.57 |
| D85_100M_CLKBUFF_MINI_DP0_R | 1619.87 | 1370.82 | 118.17 |
| D85_100M_CLKBUFF_MINI_DP1_R | 2158.02 | 1485.67 | 145.26 |
| D85_100M_CLKBUFF_MINI_DP2_R | 2525.5700000000002 | 2008.75 | 125.73 |
| D85_100M_CLKBUFF_MINI_DP3_R | 3320.35 | 2734.82 | 121.41 |
| D85_100M_CLKBUFF_RITIMER_DN | 1997.47 | 1806.03 | 110.6 |
| D85_100M_CLKBUFF_RITIMER_DP | 1999.34 | 1734.53 | 115.27 |
| D85_100M_CLKBUFF_RITIMER_R_DN | 97 | 89.37 | 108.54 |
| D85_100M_CLKBUFF_RITIMER_R_DP | 93.53 | 107.88 | 86.7 |
| D85_100M_LIGHT_DP0_R | 170.29 | 125 | 136.22999999999999 |
| D85_100M_LIGHT_DP1_R | 165.8 | 155.99 | 106.29 |
| D85_100M_LIGHT_DP2_R | 136.6 | 96 | 142.29 |
| D85_100M_LIGHT_DP3_R | 245.49 | 238.74 | 102.83 |
| D85_CLKBUFF_FB_DNC_N | 107.03 | 118.38 | 90.41 |
| D85_CLKBUFF_FB_DNC_P | 196.71 | 176.63 | 111.37 |
| D85_LEOPARD_PCIE_CLK100M_N | 2806.97 | 2544.8000000000002 | 110.3 |
| D85_LEOPARD_PCIE_CLK100M_P | 2808.16 | 2489.6999999999998 | 112.79 |
| D85_LEOPARD_PCIE_RX_C_DN0 | 1274.6300000000001 | 1009.51 | 126.26 |
| D85_LEOPARD_PCIE_RX_C_DN1 | 1205.58 | 789.01 | 152.80000000000001 |
| D85_LEOPARD_PCIE_RX_C_DN2 | 1236.52 | 837.74 | 147.6 |
| D85_LEOPARD_PCIE_RX_C_DN3 | 1341.3 | 957.24 | 140.12 |
| D85_LEOPARD_PCIE_RX_C_DN4 | 1344.59 | 1270.23 | 105.85 |
| D85_LEOPARD_PCIE_RX_C_DN5 | 1406.89 | 1401.73 | 100.37 |
| D85_LEOPARD_PCIE_RX_C_DN6 | 1497.6 | 1544.72 | 96.95 |
| D85_LEOPARD_PCIE_RX_C_DN7 | 1579.47 | 1701.21 | 92.84 |
| D85_LEOPARD_PCIE_RX_C_DN8 | 1681.32 | 1894.21 | 88.76 |
| D85_LEOPARD_PCIE_RX_C_DN9 | 1768.97 | 2010.7 | 87.98 |
| D85_LEOPARD_PCIE_RX_C_DN10 | 1924.66 | 2203.69 | 87.34 |
| D85_LEOPARD_PCIE_RX_C_DN11 | 1999.84 | 2370.19 | 84.37 |
| D85_LEOPARD_PCIE_RX_C_DN12 | 2206.1799999999998 | 2608.1799999999998 | 84.59 |
| D85_LEOPARD_PCIE_RX_C_DN13 | 2268.2399999999998 | 2754.68 | 82.34 |
| D85_LEOPARD_PCIE_RX_C_DN14 | 2462.75 | 2927.67 | 84.12 |
| D85_LEOPARD_PCIE_RX_C_DN15 | 2500.79 | 3034.17 | 82.42 |
| D85_LEOPARD_PCIE_RX_C_DP0 | 1274.67 | 1016 | 125.46 |
| D85_LEOPARD_PCIE_RX_C_DP1 | 1208.02 | 795.5 | 151.86000000000001 |
| D85_LEOPARD_PCIE_RX_C_DP2 | 1237.3499999999999 | 781.25 | 158.38 |
| D85_LEOPARD_PCIE_RX_C_DP3 | 1343.97 | 900.75 | 149.21 |
| D85_LEOPARD_PCIE_RX_C_DP4 | 1347.49 | 1213.74 | 111.02 |
| D85_LEOPARD_PCIE_RX_C_DP5 | 1410.41 | 1345.24 | 104.84 |
| D85_LEOPARD_PCIE_RX_C_DP6 | 1500.32 | 1488.23 | 100.81 |
| D85_LEOPARD_PCIE_RX_C_DP7 | 1582.46 | 1644.72 | 96.21 |
| D85_LEOPARD_PCIE_RX_C_DP8 | 1683.87 | 1837.72 | 91.63 |
| D85_LEOPARD_PCIE_RX_C_DP9 | 1772.07 | 1954.21 | 90.68 |
| D85_LEOPARD_PCIE_RX_C_DP10 | 1927.31 | 2147.1999999999998 | 89.76 |
| D85_LEOPARD_PCIE_RX_C_DP11 | 2003.66 | 2313.6999999999998 | 86.6 |
| D85_LEOPARD_PCIE_RX_C_DP12 | 2209.2600000000002 | 2551.69 | 86.58 |
| D85_LEOPARD_PCIE_RX_C_DP13 | 2268.41 | 2698.19 | 84.07 |
| D85_LEOPARD_PCIE_RX_C_DP14 | 2466.4899999999998 | 2871.18 | 85.9 |
| D85_LEOPARD_PCIE_RX_C_DP15 | 2500.2600000000002 | 2977.68 | 83.97 |
| D85_LEOPARD_PCIE_RX_DN0 | 652.20000000000005 | 773.79 | 84.29 |
| D85_LEOPARD_PCIE_RX_DN1 | 688.38 | 828.94 | 83.04 |
| D85_LEOPARD_PCIE_RX_DN2 | 702.31 | 869.82 | 80.739999999999995 |
| D85_LEOPARD_PCIE_RX_DN3 | 633.83000000000004 | 790.37 | 80.19 |
| D85_LEOPARD_PCIE_RX_DN4 | 651.09 | 802.12 | 81.17 |
| D85_LEOPARD_PCIE_RX_DN5 | 603.88 | 744.67 | 81.09 |
| D85_LEOPARD_PCIE_RX_DN6 | 543.98 | 667.17 | 81.53 |
| D85_LEOPARD_PCIE_RX_DN7 | 519.78 | 634.66999999999996 | 81.900000000000006 |
| D85_LEOPARD_PCIE_RX_DN8 | 476.28 | 567.82000000000005 | 83.88 |
| D85_LEOPARD_PCIE_RX_DN9 | 442.46 | 495.37 | 89.32 |
| D85_LEOPARD_PCIE_RX_DN10 | 448.46 | 467.87 | 95.85 |
| D85_LEOPARD_PCIE_RX_DN11 | 430.12 | 445.37 | 96.58 |
| D85_LEOPARD_PCIE_RX_DN12 | 432.6 | 462.92 | 93.45 |
| D85_LEOPARD_PCIE_RX_DN13 | 427.75 | 422.34 | 101.28 |
| D85_LEOPARD_PCIE_RX_DN14 | 431.17 | 469.79 | 91.78 |
| D85_LEOPARD_PCIE_RX_DN15 | 461.13 | 552.29 | 83.49 |
| D85_LEOPARD_PCIE_RX_DP0 | 651.64 | 838.14 | 77.75 |
| D85_LEOPARD_PCIE_RX_DP1 | 689.08 | 893.29 | 77.14 |
| D85_LEOPARD_PCIE_RX_DP2 | 702.95 | 884.22 | 79.5 |
| D85_LEOPARD_PCIE_RX_DP3 | 634.73 | 804.72 | 78.88 |
| D85_LEOPARD_PCIE_RX_DP4 | 651.04999999999995 | 816.52 | 79.73 |
| D85_LEOPARD_PCIE_RX_DP5 | 603.75 | 759.02 | 79.540000000000006 |
| D85_LEOPARD_PCIE_RX_DP6 | 544.29999999999995 | 681.52 | 79.87 |
| D85_LEOPARD_PCIE_RX_DP7 | 519.82000000000005 | 649.07000000000005 | 80.09 |
| D85_LEOPARD_PCIE_RX_DP8 | 476.55 | 582.22 | 81.849999999999994 |
| D85_LEOPARD_PCIE_RX_DP9 | 442.51 | 509.72 | 86.81 |
| D85_LEOPARD_PCIE_RX_DP10 | 449.42 | 482.27 | 93.19 |
| D85_LEOPARD_PCIE_RX_DP11 | 430.12 | 459.77 | 93.55 |
| D85_LEOPARD_PCIE_RX_DP12 | 432.61 | 477.27 | 90.64 |
| D85_LEOPARD_PCIE_RX_DP13 | 427.76 | 434.82 | 98.38 |
| D85_LEOPARD_PCIE_RX_DP14 | 431.2 | 455.44 | 94.68 |
| D85_LEOPARD_PCIE_RX_DP15 | 461.16 | 537.94000000000005 | 85.73 |
| D85_LEOPARD_PCIE_TX_DN0 | 1826.44 | 1968.54 | 92.78 |
| D85_LEOPARD_PCIE_TX_DN1 | 1788.25 | 1803.19 | 99.17 |
| D85_LEOPARD_PCIE_TX_DN2 | 1791.98 | 1708.68 | 104.87 |
| D85_LEOPARD_PCIE_TX_DN3 | 1798.82 | 1582.68 | 113.66 |
| D85_LEOPARD_PCIE_TX_DN4 | 1809.68 | 1409.47 | 128.38999999999999 |
| D85_LEOPARD_PCIE_TX_DN5 | 1826.46 | 1338.63 | 136.44 |
| D85_LEOPARD_PCIE_TX_DN6 | 1860.01 | 1559.07 | 119.3 |
| D85_LEOPARD_PCIE_TX_DN7 | 1897.27 | 1748.06 | 108.54 |
| D85_LEOPARD_PCIE_TX_DN8 | 1983.8 | 2007.91 | 98.8 |
| D85_LEOPARD_PCIE_TX_DN9 | 2048.61 | 2196.85 | 93.25 |
| D85_LEOPARD_PCIE_TX_DN10 | 2215.62 | 2417.34 | 91.66 |
| D85_LEOPARD_PCIE_TX_DN11 | 2286.85 | 2606.34 | 87.74 |
| D85_LEOPARD_PCIE_TX_DN12 | 2478.3200000000002 | 2826.78 | 87.67 |
| D85_LEOPARD_PCIE_TX_DN13 | 2554.4499999999998 | 3015.78 | 84.7 |
| D85_LEOPARD_PCIE_TX_DN14 | 2701.32 | 3236.27 | 83.47 |
| D85_LEOPARD_PCIE_TX_DN15 | 2767.87 | 3425.22 | 80.81 |
| D85_LEOPARD_PCIE_TX_DP0 | 1830.8 | 2039.38 | 89.77 |
| D85_LEOPARD_PCIE_TX_DP1 | 1790.79 | 1874.03 | 95.56 |
| D85_LEOPARD_PCIE_TX_DP2 | 1794.53 | 1779.52 | 100.84 |
| D85_LEOPARD_PCIE_TX_DP3 | 1801.69 | 1653.57 | 108.96 |
| D85_LEOPARD_PCIE_TX_DP4 | 1814.02 | 1480.31 | 122.54 |
| D85_LEOPARD_PCIE_TX_DP5 | 1830.93 | 1354.36 | 135.19 |
| D85_LEOPARD_PCIE_TX_DP6 | 1862.52 | 1488.23 | 125.15 |
| D85_LEOPARD_PCIE_TX_DP7 | 1899.8 | 1677.17 | 113.27 |
| D85_LEOPARD_PCIE_TX_DP8 | 1988.17 | 1937.02 | 102.64 |
| D85_LEOPARD_PCIE_TX_DP9 | 2052.1799999999998 | 2126.0100000000002 | 96.53 |
| D85_LEOPARD_PCIE_TX_DP10 | 2219.1799999999998 | 2346.5 | 94.57 |
| D85_LEOPARD_PCIE_TX_DP11 | 2290.7800000000002 | 2535.4499999999998 | 90.35 |
| D85_LEOPARD_PCIE_TX_DP12 | 2481.14 | 2755.94 | 90.03 |
| D85_LEOPARD_PCIE_TX_DP13 | 2558.33 | 2944.94 | 86.87 |
| D85_LEOPARD_PCIE_TX_DP14 | 2703.81 | 3165.38 | 85.42 |
| D85_LEOPARD_PCIE_TX_DP15 | 2771.47 | 3354.38 | 82.62 |
| D85_LEOPARD_USB_DN | 2599.62 | 3409.03 | 76.260000000000005 |
| D85_LEOPARD_USB_DP | 2597.9899999999998 | 3386.43 | 76.72 |
| D85_LIGHT_DOWNSTREAM_PCIE_C_TX_DN0 | 743.22 | 945.15 | 78.63 |
| D85_LIGHT_DOWNSTREAM_PCIE_C_TX_DN1 | 680.02 | 833.34 | 81.599999999999994 |
| D85_LIGHT_DOWNSTREAM_PCIE_C_TX_DN2 | 734.29 | 838.33 | 87.59 |
| D85_LIGHT_DOWNSTREAM_PCIE_C_TX_DN3 | 591.05999999999995 | 708.14 | 83.47 |
| D85_LIGHT_DOWNSTREAM_PCIE_C_TX_DN4 | 738.56 | 857.13 | 86.17 |
| D85_LIGHT_DOWNSTREAM_PCIE_C_TX_DN5 | 627.02 | 701.32 | 89.41 |
| D85_LIGHT_DOWNSTREAM_PCIE_C_TX_DN6 | 690.82 | 730.93 | 94.51 |
| D85_LIGHT_DOWNSTREAM_PCIE_C_TX_DN7 | 581.9 | 597.79999999999995 | 97.34 |
| D85_LIGHT_DOWNSTREAM_PCIE_C_TX_DN8 | 683.46 | 700.8 | 97.53 |
| D85_LIGHT_DOWNSTREAM_PCIE_C_TX_DN9 | 611.11 | 597.70000000000005 | 102.24 |
| D85_LIGHT_DOWNSTREAM_PCIE_C_TX_DN10 | 627.49 | 635.02 | 98.81 |
| D85_LIGHT_DOWNSTREAM_PCIE_C_TX_DN11 | 603.5 | 635.52 | 94.96 |
| D85_LIGHT_DOWNSTREAM_PCIE_C_TX_DN12 | 706.26 | 740.53 | 95.37 |
| D85_LIGHT_DOWNSTREAM_PCIE_C_TX_DN13 | 670.42 | 730.03 | 91.83 |
| D85_LIGHT_DOWNSTREAM_PCIE_C_TX_DN14 | 649.5 | 755.66 | 85.95 |
| D85_LIGHT_DOWNSTREAM_PCIE_C_TX_DN15 | 669.4 | 781.23 | 85.69 |
| D85_LIGHT_DOWNSTREAM_PCIE_C_TX_DP0 | 743.87 | 888.66 | 83.71 |
| D85_LIGHT_DOWNSTREAM_PCIE_C_TX_DP1 | 682.41 | 778.16 | 87.7 |
| D85_LIGHT_DOWNSTREAM_PCIE_C_TX_DP2 | 736.06 | 784.84 | 93.78 |
| D85_LIGHT_DOWNSTREAM_PCIE_C_TX_DP3 | 592.86 | 651.65 | 90.98 |
| D85_LIGHT_DOWNSTREAM_PCIE_C_TX_DP4 | 742.38 | 800.64 | 92.72 |
| D85_LIGHT_DOWNSTREAM_PCIE_C_TX_DP5 | 629.55999999999995 | 647.14 | 97.28 |
| D85_LIGHT_DOWNSTREAM_PCIE_C_TX_DP6 | 694.85 | 676.75 | 102.67 |
| D85_LIGHT_DOWNSTREAM_PCIE_C_TX_DP7 | 584.19000000000005 | 543.62 | 107.46 |
| D85_LIGHT_DOWNSTREAM_PCIE_C_TX_DP8 | 685.98 | 646.62 | 106.09 |
| D85_LIGHT_DOWNSTREAM_PCIE_C_TX_DP9 | 614.29 | 591.21 | 103.9 |
| D85_LIGHT_DOWNSTREAM_PCIE_C_TX_DP10 | 630.41 | 626.22 | 100.67 |
| D85_LIGHT_DOWNSTREAM_PCIE_C_TX_DP11 | 607.23 | 626.72 | 96.89 |
| D85_LIGHT_DOWNSTREAM_PCIE_C_TX_DP12 | 708.53 | 732.73 | 96.7 |
| D85_LIGHT_DOWNSTREAM_PCIE_C_TX_DP13 | 672.54 | 722.23 | 93.12 |
| D85_LIGHT_DOWNSTREAM_PCIE_C_TX_DP14 | 652.34 | 746.86 | 87.34 |
| D85_LIGHT_DOWNSTREAM_PCIE_C_TX_DP15 | 669.17 | 774.74 | 86.37 |
| D85_LIGHT_DOWNSTREAM_PCIE_RX_DN0 | 2668.84 | 2844.48 | 93.83 |
| D85_LIGHT_DOWNSTREAM_PCIE_RX_DN1 | 2490.27 | 2726.37 | 91.34 |
| D85_LIGHT_DOWNSTREAM_PCIE_RX_DN2 | 2459.85 | 2700.78 | 91.08 |
| D85_LIGHT_DOWNSTREAM_PCIE_RX_DN3 | 2581.39 | 2881.89 | 89.57 |
| D85_LIGHT_DOWNSTREAM_PCIE_RX_DN4 | 2477.1 | 2600.39 | 95.26 |
| D85_LIGHT_DOWNSTREAM_PCIE_RX_DN5 | 2324.7199999999998 | 2482.2800000000002 | 93.65 |
| D85_LIGHT_DOWNSTREAM_PCIE_RX_DN6 | 2378.04 | 2456.69 | 96.8 |
| D85_LIGHT_DOWNSTREAM_PCIE_RX_DN7 | 2531.4499999999998 | 2637.79 | 95.97 |
| D85_LIGHT_DOWNSTREAM_PCIE_RX_DN8 | 2420.06 | 2356.3000000000002 | 102.71 |
| D85_LIGHT_DOWNSTREAM_PCIE_RX_DN9 | 2277.4499999999998 | 2238.1799999999998 | 101.75 |
| D85_LIGHT_DOWNSTREAM_PCIE_RX_DN10 | 2328.83 | 2212.58 | 105.25 |
| D85_LIGHT_DOWNSTREAM_PCIE_RX_DN11 | 2509.79 | 2393.69 | 104.85 |
| D85_LIGHT_DOWNSTREAM_PCIE_RX_DN12 | 2438.35 | 2450.7800000000002 | 99.49 |
| D85_LIGHT_DOWNSTREAM_PCIE_RX_DN13 | 2317.2199999999998 | 2269.67 | 102.1 |
| D85_LIGHT_DOWNSTREAM_PCIE_RX_DN14 | 2522.75 | 2295.27 | 109.91 |
| D85_LIGHT_DOWNSTREAM_PCIE_RX_DN15 | 2185.6 | 1967.33 | 111.09 |
| D85_LIGHT_DOWNSTREAM_PCIE_RX_DP0 | 2672.78 | 2728.34 | 97.96 |
| D85_LIGHT_DOWNSTREAM_PCIE_RX_DP1 | 2492.8000000000002 | 2610.2399999999998 | 95.5 |
| D85_LIGHT_DOWNSTREAM_PCIE_RX_DP2 | 2462.34 | 2584.65 | 95.27 |
| D85_LIGHT_DOWNSTREAM_PCIE_RX_DP3 | 2584.2199999999998 | 2765.75 | 93.44 |
| D85_LIGHT_DOWNSTREAM_PCIE_RX_DP4 | 2481.48 | 2484.25 | 99.89 |
| D85_LIGHT_DOWNSTREAM_PCIE_RX_DP5 | 2328.62 | 2366.15 | 98.41 |
| D85_LIGHT_DOWNSTREAM_PCIE_RX_DP6 | 2382.35 | 2340.56 | 101.79 |
| D85_LIGHT_DOWNSTREAM_PCIE_RX_DP7 | 2535.36 | 2521.65 | 100.54 |
| D85_LIGHT_DOWNSTREAM_PCIE_RX_DP8 | 2422.62 | 2240.16 | 108.14 |
| D85_LIGHT_DOWNSTREAM_PCIE_RX_DP9 | 2280.33 | 2122.0500000000002 | 107.46 |
| D85_LIGHT_DOWNSTREAM_PCIE_RX_DP10 | 2332.41 | 2096.46 | 111.25 |
| D85_LIGHT_DOWNSTREAM_PCIE_RX_DP11 | 2513.08 | 2277.56 | 110.34 |
| D85_LIGHT_DOWNSTREAM_PCIE_RX_DP12 | 2442.1999999999998 | 2393.6999999999998 | 102.03 |
| D85_LIGHT_DOWNSTREAM_PCIE_RX_DP13 | 2319.9699999999998 | 2212.6 | 104.85 |
| D85_LIGHT_DOWNSTREAM_PCIE_RX_DP14 | 2526.88 | 2238.19 | 112.9 |
| D85_LIGHT_DOWNSTREAM_PCIE_RX_DP15 | 2185.21 | 1910.69 | 114.37 |
| D85_LIGHT_DOWNSTREAM_PCIE_TX_DN0 | 1737.49 | 1672.61 | 103.88 |
| D85_LIGHT_DOWNSTREAM_PCIE_TX_DN1 | 1648.32 | 1666.31 | 98.92 |
| D85_LIGHT_DOWNSTREAM_PCIE_TX_DN2 | 1564.73 | 1635.73 | 95.66 |
| D85_LIGHT_DOWNSTREAM_PCIE_TX_DN3 | 1823.12 | 1947.03 | 93.64 |
| D85_LIGHT_DOWNSTREAM_PCIE_TX_DN4 | 1630.37 | 1516.54 | 107.51 |
| D85_LIGHT_DOWNSTREAM_PCIE_TX_DN5 | 1586.27 | 1554.24 | 102.06 |
| D85_LIGHT_DOWNSTREAM_PCIE_TX_DN6 | 1447.37 | 1499.04 | 96.55 |
| D85_LIGHT_DOWNSTREAM_PCIE_TX_DN7 | 1753.24 | 1813.27 | 96.69 |
| D85_LIGHT_DOWNSTREAM_PCIE_TX_DN8 | 1602.58 | 1428.78 | 112.16 |
| D85_LIGHT_DOWNSTREAM_PCIE_TX_DN9 | 1470.36 | 1439.86 | 102.12 |
| D85_LIGHT_DOWNSTREAM_PCIE_TX_DN10 | 1595.67 | 1467.58 | 108.73 |
| D85_LIGHT_DOWNSTREAM_PCIE_TX_DN11 | 1752.25 | 1697.19 | 103.24 |
| D85_LIGHT_DOWNSTREAM_PCIE_TX_DN12 | 1599.55 | 1483.53 | 107.82 |
| D85_LIGHT_DOWNSTREAM_PCIE_TX_DN13 | 1463.18 | 1328.1 | 110.17 |
| D85_LIGHT_DOWNSTREAM_PCIE_TX_DN14 | 1639.46 | 1389.91 | 117.95 |
| D85_LIGHT_DOWNSTREAM_PCIE_TX_DN15 | 1745.46 | 1582.81 | 110.28 |
| D85_LIGHT_DOWNSTREAM_PCIE_TX_DP0 | 1736.66 | 1612.96 | 107.67 |
| D85_LIGHT_DOWNSTREAM_PCIE_TX_DP1 | 1649.06 | 1605.35 | 102.72 |
| D85_LIGHT_DOWNSTREAM_PCIE_TX_DP2 | 1565 | 1573.08 | 99.49 |
| D85_LIGHT_DOWNSTREAM_PCIE_TX_DP3 | 1823.4 | 1887.38 | 96.61 |
| D85_LIGHT_DOWNSTREAM_PCIE_TX_DP4 | 1629.7 | 1456.89 | 111.86 |
| D85_LIGHT_DOWNSTREAM_PCIE_TX_DP5 | 1586.01 | 1492.28 | 106.28 |
| D85_LIGHT_DOWNSTREAM_PCIE_TX_DP6 | 1447.4 | 1437.08 | 100.72 |
| D85_LIGHT_DOWNSTREAM_PCIE_TX_DP7 | 1753.92 | 1751.31 | 100.15 |
| D85_LIGHT_DOWNSTREAM_PCIE_TX_DP8 | 1602.78 | 1366.82 | 117.26 |
| D85_LIGHT_DOWNSTREAM_PCIE_TX_DP9 | 1471.35 | 1380.21 | 106.6 |
| D85_LIGHT_DOWNSTREAM_PCIE_TX_DP10 | 1596.61 | 1405.63 | 113.59 |
| D85_LIGHT_DOWNSTREAM_PCIE_TX_DP11 | 1752.68 | 1635.24 | 107.18 |
| D85_LIGHT_DOWNSTREAM_PCIE_TX_DP12 | 1599.8 | 1434.25 | 111.54 |
| D85_LIGHT_DOWNSTREAM_PCIE_TX_DP13 | 1463.69 | 1267.1400000000001 | 115.51 |
| D85_LIGHT_DOWNSTREAM_PCIE_TX_DP14 | 1640.07 | 1327.96 | 123.5 |
| D85_LIGHT_DOWNSTREAM_PCIE_TX_DP15 | 1744.95 | 1523.17 | 114.56 |
| D85_RETIMER_USB_DN | 186.33 | 118 | 157.91 |
| D85_RETIMER_USB_DP | 190.53 | 218 | 87.4 |
| D85_RETIMER_USB_R_DN | 297.97000000000003 | 359.13 | 82.97 |
| D85_RETIMER_USB_R_DP | 297.45 | 318.81 | 93.3 |
| D85_SI_RX_DN15 | 494.06 | 550.04999999999995 | 89.82 |
| D85_SI_RX_DN15_R | 26.41 | 27 | 97.83 |
| D85_SI_RX_DP15 | 498.24 | 543.55999999999995 | 91.66 |
| D85_SI_RX_DP15_R | 27 | 27 | 100 |
| D85_USB_CON_DN | 622.75 | 647.78 | 96.14 |
| D85_USB_CON_DP | 619.95000000000005 | 463.04 | 133.88999999999999 |
| D85_USB_HUB_MINI_A_DN | 3090.3 | 2850.26 | 108.42 |
| D85_USB_HUB_MINI_A_DN_R | 555.03 | 469.78 | 118.15 |
| D85_USB_HUB_MINI_A_DP | 3092.92 | 2860.56 | 108.12 |
| D85_USB_HUB_MINI_A_DP_R | 556.62 | 595.42999999999995 | 93.48 |
| D85_USB_HUB_MINI_B_DN | 3072.58 | 2968.87 | 103.49 |
| D85_USB_HUB_MINI_B_DN_R | 1114.1199999999999 | 1071.8499999999999 | 103.94 |
| D85_USB_HUB_MINI_B_DP | 3072.53 | 2990.19 | 102.75 |
| D85_USB_HUB_MINI_B_DP_R | 1113.3 | 1197.5 | 92.97 |
| D85_USB_HUB_MINI_C_DN | 3242.65 | 3212.81 | 100.93 |
| D85_USB_HUB_MINI_C_DN_R | 1529.14 | 1358.93 | 112.53 |
| D85_USB_HUB_MINI_C_DP | 3242.12 | 3233.13 | 100.28 |
| D85_USB_HUB_MINI_C_DP_R | 1532.01 | 1403.57 | 109.15 |
| D85_USB_HUB_MINI_D_DN | 3462.46 | 3359.44 | 103.07 |
| D85_USB_HUB_MINI_D_DN_R | 2142.94 | 1669.22 | 128.38 |
| D85_USB_HUB_MINI_D_DP | 3464.11 | 3376.26 | 102.6 |
| D85_USB_HUB_MINI_D_DP_R | 2143.75 | 1683.62 | 127.33 |
| DIG_GND_CLOCK | 128.54 | 29.37 | 437.66 |
| GND | 23253.81 | 50102.45 | 46.41 |
| N22743671 | 410.78 | 476.43 | 86.22 |
| N22744294 | 374.04 | 466.33 | 80.209999999999994 |
| P12V | 4367.3 | 9148.26 | 47.74 |
| P1V0 | 4522.7 | 6962.38 | 64.959999999999994 |
| P1V8 | 3369.53 | 8988.93 | 37.49 |
| P1V0_A | 1555.7 | 5794.88 | 26.85 |
| P1V0_A_CC | 1411.31 | 925.5 | 152.49 |
| P1V0_A_CC_R | 258.91000000000003 | 163 | 158.84 |
| P1V0_A_EN | 144.54 | 99 | 146 |
| P1V0_A_EN_R | 203.43 | 159.44 | 127.59 |
| P1V0_A_OUT | 282.05 | 859 | 32.840000000000003 |
| P1V0_A_SNB | 142.5 | 87 | 163.79 |
| P1V0_A_SS | 134.03 | 138.82 | 96.55 |
| P1V0_A_SW | 515.85 | 718.36 | 71.81 |
| P1V0_A_VBST | 168.49 | 193.01 | 87.3 |
| P1V0_A_VBST_RR | 88.97 | 47.02 | 189.22 |
| P1V0_A_VCC | 204.89 | 100.72 | 203.42 |
| P1V0_A_VFB | 265.18 | 220.97 | 120.01 |
| P1V0_A_VFB_R | 1013.88 | 647.5 | 156.58000000000001 |
| P1V0_A_VIN | 72 | 381.6 | 18.87 |
| P1V0_A_VO | 157.15 | 158.03 | 99.44 |
| P1V0_A_VRG5 | 177.88 | 174.83 | 101.75 |
| P1V0_CC | 1405.07 | 915.5 | 153.47999999999999 |
| P1V0_CC_R | 229.13 | 151.28 | 151.46 |
| P1V0_EN | 140.41999999999999 | 87 | 161.4 |
| P1V0_EN_R | 196.87 | 113.1 | 174.07 |
| P1V0_OUT | 306.47000000000003 | 885 | 34.630000000000003 |
| P1V0_SNB | 72.36 | 87 | 83.17 |
| P1V0_SS | 137.08000000000001 | 143.94 | 95.23 |
| P1V0_SW | 509.91 | 729.36 | 69.91 |
| P1V0_VBST | 152.36000000000001 | 175.67 | 86.73 |
| P1V0_VBST_RR | 44.31 | 44.54 | 99.47 |
| P1V0_VCC | 205.27 | 96.85 | 211.94 |
| P1V0_VFB | 265.56 | 217.87 | 121.89 |
| P1V0_VFB_R | 1028.58 | 673.5 | 152.72 |
| P1V0_VIN | 138.01 | 386.97 | 35.659999999999997 |
| P1V0_VO | 166.16 | 167.03 | 99.48 |
| P1V0_VRG5 | 177.99 | 174.3 | 102.12 |
| P1V8_CC | 1605.2 | 930.5 | 172.51 |
| P1V8_CC_R | 242.81 | 168 | 144.53 |
| P1V8_EN | 129 | 80 | 161.25 |
| P1V8_EN_R | 190.22 | 120.1 | 158.38 |
| P1V8_OUT | 244.26 | 876 | 27.88 |
| P1V8_SNB | 72.77 | 88 | 82.69 |
| P1V8_SS | 139.1 | 164.33 | 84.65 |
| P1V8_SW | 450.47 | 717.24 | 62.81 |
| P1V8_VBST | 158.1 | 187.52 | 84.31 |
| P1V8_VBST_RR | 44.46 | 45.53 | 97.66 |
| P1V8_VCC | 176.47 | 101.99 | 173.02 |
| P1V8_VDDA_CLKBUFF | 1169.3399999999999 | 871.13 | 134.22999999999999 |
| P1V8_VDDA_CLKBUFF_R | 95.38 | 60 | 158.97 |
| P1V8_VDDIO_CLKBUFF | 1912.64 | 1059.3699999999999 | 180.55 |
| P1V8_VDDIO_CLKBUFF_R | 109.47 | 74 | 147.93 |
| P1V8_VDD_1D8_CLKBUFF | 800.89 | 644.76 | 124.22 |
| P1V8_VDD_1D8_CLKBUFF_R | 107 | 50 | 214 |
| P1V8_VDD_D_CLKBUFF | 674.28 | 570.87 | 118.11 |
| P1V8_VDD_D_CLKBUFF_R | 128.05000000000001 | 89 | 143.88 |
| P1V8_VFB | 270.70999999999998 | 222.97 | 121.41 |
| P1V8_VFB_R | 1140.77 | 657.5 | 173.5 |
| P1V8_VIN | 102.4 | 381.97 | 26.81 |
| P1V8_VO | 154.61000000000001 | 154.03 | 100.38 |
| P1V8_VRG5 | 195.49 | 192.11 | 101.76 |
| P3V3 | 11495.24 | 14764.84 | 77.86 |
| P3V3_AUX | 14510.43 | 11636.39 | 124.7 |
| P5V_MINI_USB | 138.05000000000001 | 452.75 | 30.49 |
| PWRGD_P1V0 | 1493.84 | 1144.6600000000001 | 130.51 |
| PWRGD_P1V8 | 1160.8 | 1085.57 | 106.93 |
| PWRGD_P1V0_A | 359.18 | 263.54000000000002 | 136.29 |
| PWRGD_P1V8_R | 321.06 | 323.95999999999998 | 99.1 |
| PWR_BRK# | 760.72 | 979.68 | 77.650000000000006 |
| Z50_EEPROM_ADD_A0 | 176.38 | 97.5 | 180.9 |
| Z50_EEPROM_ADD_A1 | 160.5 | 87.5 | 183.43 |
| Z50_EEPROM_ADD_A2 | 182.31 | 97.5 | 186.98 |
| Z50_HUB_PLLFILT_TP | 149.08000000000001 | 127.16 | 117.24 |
| Z50_ISOLATION_1_GATE | 126.65 | 139.5 | 90.79 |
| Z50_ISOLATION_D1_GATE | 219.14 | 172.11 | 127.33 |
| Z50_ISOLATION_D_GATE | 160.93 | 172.5 | 93.29 |
| Z50_ISOLATION_GATE | 329.03 | 141.5 | 232.53 |
| Z50_RITIMER_EEPROM_MASTER_I2C_SCL | 3358.03 | 3175.75 | 105.74 |
| Z50_RITIMER_EEPROM_MASTER_I2C_SDA | 3365.19 | 3044.25 | 110.54 |
| Z50_RITIMER_JTAG_TCK | 113.54 | 123.5 | 91.94 |
| Z50_RITIMER_JTAG_TCK_R | 1483.29 | 1606.73 | 92.32 |
| Z50_RITIMER_JTAG_TDI | 101.91 | 102.5 | 99.43 |
| Z50_RITIMER_JTAG_TDI_R | 1266.6300000000001 | 1298.23 | 97.57 |
| Z50_RITIMER_JTAG_TDO | 115.9 | 119.8 | 96.75 |
| Z50_RITIMER_JTAG_TDO_R | 1473.83 | 1480.43 | 99.55 |
| Z50_RITIMER_JTAG_TMS | 107.91 | 108.5 | 99.46 |
| Z50_RITIMER_JTAG_TMS_R | 1527.84 | 1586.73 | 96.29 |
| Z50_RITIMER_JTAG_TRST | 1171.08 | 994.53 | 117.75 |
| Z50_RITIMER_JTAG_TRST_R | 378.56 | 369.2 | 102.54 |
| Z50_RITIMER_MASTER_I2C_ADD_A0 | 547.61 | 517.22 | 105.88 |
| Z50_RITIMER_MASTER_I2C_ADD_A1 | 456.77 | 445.72 | 102.48 |
| Z50_RITIMER_MASTER_I2C_ADD_A2 | 377.28 | 423.18 | 89.15 |
| Z50_RITIMER_MASTER_I2C_ADD_A3 | 376.97 | 458.54 | 82.21 |
| Z50_RITIMER_MASTER_I2C_EESIZE | 645.41 | 656.13 | 98.37 |
| Z50_RITIMER_MASTER_I2C_SMODE | 697.8 | 733.13 | 95.18 |
| Z50_RITIMER_SLAVE_I2C_ADD_A0 | 722.67 | 626.02 | 115.44 |
| Z50_RITIMER_SLAVE_I2C_ADD_A1 | 635.1 | 528.52 | 120.17 |
| Z50_RITIMER_SLAVE_I2C_ADD_A2 | 537.04999999999995 | 477.03 | 112.58 |
| Z50_RITIMER_SLAVE_I2C_ADD_A5 | 472.31 | 482.53 | 97.88 |
| Z50_RSVD | 458.89 | 492.93 | 93.09 |
| Z50_USB_CRFILT_TP | 165.92 | 93 | 178.41 |
| Z50_USB_HUB_CONFIGURE_SEL0 | 230.47 | 156.54 | 147.22999999999999 |
| Z50_USB_HUB_CONFIGURE_SEL1 | 197.92 | 178.3 | 111.01 |
| Z50_USB_HUB_XTAL_IN | 314.98 | 325.20999999999998 | 96.85 |
| Z50_USB_HUB_XTAL_OUT | 192.97 | 193.1 | 99.93 |
| Z50_USB_NON_REM0 | 270.77999999999997 | 271.19 | 99.85 |
| Z50_USB_NON_REM1 | 252.48 | 205.73 | 122.72 |
| Z50_USB_OCS_N1 | 140.21 | 155.21 | 90.34 |
| Z50_USB_OCS_N2 | 151.21 | 95.44 | 158.44 |
| Z50_USB_OCS_N3 | 209.63 | 196.35 | 106.76 |
| Z50_USB_OCS_N4 | 142.12 | 94.45 | 150.47 |
| Z50_USB_PRTPWR_EN1 | 223.32 | 182.45 | 122.4 |
| Z50_USB_PRTPWR_EN2 | 174.31 | 112.26 | 155.27000000000001 |
| Z50_USB_PRTPWR_EN3 | 291.8 | 180.83 | 161.37 |
| Z50_USB_PRTPWR_EN4 | 212.11 | 221.46 | 95.78 |
| Z50_USB_RBIAS | 86.64 | 97.44 | 88.91 |
| Z50_USB_VBUS_DET | 157.53 | 192.95 | 81.64 |
| ZDEC_CLKBUFF_OE0# | 220.01 | 223.13 | 98.6 |
| ZDEC_CLKBUFF_OE1# | 3637.52 | 2454.64 | 148.19 |
| ZDEC_CLKBUFF_OE2# | 3125.58 | 2733.66 | 114.34 |
| ZDEC_CLKBUFF_OE3# | 3127.35 | 2908.14 | 107.54 |
| ZDEC_CLKBUFF_OE4# | 3243.72 | 3109.75 | 104.31 |
| ZDEC_CLKBUFF_OE5# | 271.37 | 143 | 189.77 |
| ZDEF_CLKBUFF_CKPWRGD_PD# | 192.94 | 107.63 | 179.27 |
| ZDEF_CLKBUFF_HIBW_BYPM_LOBW# | 177.26 | 119.38 | 148.47999999999999 |
| ZDEF_CLKBUFF_SMB_ADDR | 236.34 | 143.63 | 164.54 |
| ZDEF_CLOCKBUFF_I2C_CLK_R | 175.75 | 204.38 | 85.99 |
| ZDEF_CLOCKBUFF_I2C_DATA_R | 151.63 | 180.63 | 83.95 |
| ZDEF_DRIVE_1X16_LED | 331.05 | 321 | 103.13 |
| ZDEF_DRIVE_2X8_LED | 184.54 | 215 | 85.83 |
| ZDEF_DRIVE_4X4_LED | 589.66999999999996 | 562 | 104.92 |
| ZDEF_EEPROM_ADD_E0 | 198.87 | 102.5 | 194.02 |
| ZDEF_EEPROM_ADD_E1 | 230.77 | 144.13 | 160.11000000000001 |
| ZDEF_EEPROM_ADD_E2 | 213.2 | 155.13 | 137.44 |
| ZDEF_EEPROM_WP | 149.43 | 97.5 | 153.26 |
| ZDEF_I2C_DATA_ZDEF_MINISAS_A_CBL_PRSNT# | 923.31 | 732.8 | 126 |
| ZDEF_I2C_DATA_ZDEF_MINISAS_B_CBL_PRSNT# | 865.15 | 841.71 | 102.78 |
| ZDEF_I2C_DATA_ZDEF_MINISAS_C_CBL_PRSNT# | 852.3 | 870.78 | 97.88 |
| ZDEF_I2C_DATA_ZDEF_MINISAS_D_CBL_PRSNT# | 1117.71 | 1120.8499999999999 | 99.72 |
| ZDEF_I2C_SWITCH_ADDRESS_A0 | 242 | 232.6 | 104.04 |
| ZDEF_I2C_SWITCH_ADDRESS_A1 | 246.27 | 154.80000000000001 | 159.09 |
| ZDEF_I2C_SWITCH_ADDRESS_A2 | 271.19 | 152.5 | 177.83 |
| ZDEF_IOEXP_I2C_CLK | 271.83 | 279.61 | 97.22 |
| ZDEF_IOEXP_I2C_DATA | 310.35000000000002 | 347.21 | 89.38 |
| ZDEF_LED1X16_GATE | 288.57 | 266.75 | 108.18 |
| ZDEF_LED2X8_GATE | 397.9 | 329.25 | 120.85 |
| ZDEF_LED4X4_GATE | 339.07 | 248.25 | 136.59 |
| ZDEF_LEOPARD_GF_I2C_CLK | 5252.51 | 4552.93 | 115.37 |
| ZDEF_LEOPARD_GF_I2C_CLK_EVT2 | 1048.32 | 1083.33 | 96.77 |
| ZDEF_LEOPARD_GF_I2C_CLK_U11 | 722.74 | 563.5 | 128.26 |
| ZDEF_LEOPARD_GF_I2C_CLK_U46 | 75.2 | 87.5 | 85.94 |
| ZDEF_LEOPARD_GF_I2C_DATA | 5000.9399999999996 | 4638.58 | 107.81 |
| ZDEF_LEOPARD_GF_I2C_DATA_EVT2 | 1107.72 | 1167.73 | 94.86 |
| ZDEF_LEOPARD_GF_I2C_DATA_U11 | 707.15 | 574.1 | 123.18 |
| ZDEF_LEOPARD_GF_I2C_DATA_U46 | 73.13 | 82.5 | 88.64 |
| ZDEF_LEOPARD_ISO_I2C_CLK | 7937.97 | 5529 | 143.57 |
| ZDEF_LEOPARD_ISO_I2C_DATA | 7509 | 5689.2 | 131.99 |
| ZDEF_LEOPARD_PERST# | 8658.2199999999993 | 5500.72 | 157.4 |
| ZDEF_LEOPARD_PRSNT3_PU | 352.21 | 422.5 | 83.36 |
| ZDEF_LEOPARD_PRSNT4_PU | 333.57 | 337.5 | 98.83 |
| ZDEF_LEOPARD_PRSNT6_PU | 352.21 | 422.5 | 83.36 |
| ZDEF_LEOPARD_PRSNT_N | 685.78 | 741.13 | 92.53 |
| ZDEF_LEOPARD_SETPCIE_PRSNT3_N | 7565.95 | 6845.53 | 110.52 |
| ZDEF_LEOPARD_SETPCIE_PRSNT3_N_PD | 135.63999999999999 | 182.5 | 74.319999999999993 |
| ZDEF_LEOPARD_SETPCIE_PRSNT4_N | 5049.95 | 4520.9799999999996 | 111.7 |
| ZDEF_LEOPARD_SETPCIE_PRSNT4_N_PD | 104.57 | 107.5 | 97.28 |
| ZDEF_LEOPARD_SETPCIE_PRSNT6_N | 8011.19 | 7948.73 | 100.79 |
| ZDEF_LEOPARD_SETPCIE_PRSNT6_N_PD | 135.63999999999999 | 182.5 | 74.319999999999993 |
| ZDEF_LIGHT_I2C_MUX_INT# | 1571.6 | 1038.73 | 151.30000000000001 |
| ZDEF_LIGHT_MINISAS_A_I2C_CLK | 2393.65 | 2067.1 | 115.8 |
| ZDEF_LIGHT_MINISAS_A_I2C_CLK_R | 415.64 | 344.3 | 120.72 |
| ZDEF_LIGHT_MINISAS_A_I2C_DATA | 2621.68 | 2187.9 | 119.83 |
| ZDEF_LIGHT_MINISAS_A_I2C_DATA_R | 254.31 | 201.7 | 126.09 |
| ZDEF_LIGHT_MINISAS_A_I2C_INT# | 2164.81 | 1367 | 158.36000000000001 |
| ZDEF_LIGHT_MINISAS_B_I2C_CLK | 1455.53 | 1101.92 | 132.09 |
| ZDEF_LIGHT_MINISAS_B_I2C_CLK_R | 431.38 | 487.38 | 88.51 |
| ZDEF_LIGHT_MINISAS_B_I2C_DATA | 1492.16 | 1238.06 | 120.52 |
| ZDEF_LIGHT_MINISAS_B_I2C_DATA_R | 418.37 | 394.5 | 106.05 |
| ZDEF_LIGHT_MINISAS_B_I2C_INT# | 2069.17 | 1661.8 | 124.51 |
| ZDEF_LIGHT_MINISAS_C_I2C_CLK | 1269.01 | 1143.1300000000001 | 111.01 |
| ZDEF_LIGHT_MINISAS_C_I2C_CLK_R | 256.77 | 306.5 | 83.77 |
| ZDEF_LIGHT_MINISAS_C_I2C_DATA | 1782.24 | 1317.36 | 135.29 |
| ZDEF_LIGHT_MINISAS_C_I2C_DATA_R | 243.49 | 265.74 | 91.63 |
| ZDEF_LIGHT_MINISAS_C_I2C_INT# | 2744.59 | 2335.4 | 117.52 |
| ZDEF_LIGHT_MINISAS_D_I2C_CLK | 770.22 | 738.39 | 104.31 |
| ZDEF_LIGHT_MINISAS_D_I2C_CLK_R | 549.42999999999995 | 490.3 | 112.06 |
| ZDEF_LIGHT_MINISAS_D_I2C_DATA | 881.94 | 1007.33 | 87.55 |
| ZDEF_LIGHT_MINISAS_D_I2C_DATA_R | 311.76 | 403.01 | 77.36 |
| ZDEF_LIGHT_MINISAS_D_I2C_INT# | 2945.49 | 2517.2399999999998 | 117.01 |
| ZDEF_MINISAS_A_CBL_PRSNT# | 4766.3100000000004 | 3729.1 | 127.81 |
| ZDEF_MINISAS_A_CBL_PRSNT#_ZDEF_I2C_DATA | 973.51 | 652.20000000000005 | 149.27000000000001 |
| ZDEF_MINISAS_A_R_CBL_PRSNT# | 82.98 | 91.75 | 90.44 |
| ZDEF_MINISAS_B_CBL_PRSNT# | 4769.6899999999996 | 3425.7 | 139.22999999999999 |
| ZDEF_MINISAS_B_CBL_PRSNT#_ZDEF_I2C_DATA | 875.27 | 692.11 | 126.46 |
| ZDEF_MINISAS_B_R_CBL_PRSNT# | 77.02 | 77.349999999999994 | 99.57 |
| ZDEF_MINISAS_C_CBL_PRSNT# | 4783.41 | 3380.5 | 141.5 |
| ZDEF_MINISAS_C_CBL_PRSNT#_ZDEF_I2C_DATA | 819.88 | 721.18 | 113.69 |
| ZDEF_MINISAS_C_R_CBL_PRSNT# | 132.93 | 90.61 | 146.69999999999999 |
| ZDEF_MINISAS_D_CBL_PRSNT# | 5422.17 | 3791 | 143.03 |
| ZDEF_MINISAS_D_CBL_PRSNT#_ZDEF_I2C_DATA | 951.17 | 971.25 | 97.93 |
| ZDEF_MINISAS_D_R_CBL_PRSNT# | 121.14 | 134.44999999999999 | 90.1 |
| ZDEF_MINI_SAS_A_PERST# | 786.79 | 713.22 | 110.32 |
| ZDEF_MINI_SAS_B_PERST# | 733.26 | 798.07 | 91.88 |
| ZDEF_MINI_SAS_C_PERST# | 743.65 | 827.15 | 89.91 |
| ZDEF_MINI_SAS_D_PERST# | 912.64 | 1115.22 | 81.84 |
| ZDEF_PCIECONFIG_GATE | 183.58 | 107.1 | 171.41 |
| ZDEF_PCIECONFIG_GATE1 | 184.6 | 125.1 | 147.57 |
| ZDEF_PEB_MINISAS_A_I2C_CLK | 584.69000000000005 | 655.61 | 89.18 |
| ZDEF_PEB_MINISAS_B_I2C_CLK | 573.30999999999995 | 605.54 | 94.68 |
| ZDEF_PEB_MINISAS_C_I2C_CLK | 630 | 673.08 | 93.6 |
| ZDEF_PEB_MINISAS_D_I2C_CLK | 656.71 | 770.61 | 85.22 |
| ZDEF_PRSNT3_D | 312.55 | 327.5 | 95.43 |
| ZDEF_PRSNT6_D | 409.73 | 438.5 | 93.44 |
| ZDEF_PRSNT_GATE | 171.34 | 171.1 | 100.14 |
| ZDEF_PRSNT_GATE1 | 225.75 | 168.1 | 134.29 |
| ZDEF_PRSNT_GATE2 | 188.65 | 151.5 | 124.52 |
| ZDEF_PRSNT_GATE3 | 208.27 | 86.7 | 240.22 |
| ZDEF_PWR_STATUS_LED_EN | 252.77 | 175.25 | 144.22999999999999 |
| ZDEF_RETIMER_PRTRST#0 | 145.03 | 78.540000000000006 | 184.66 |
| ZDEF_RETIMER_PRTRST#1 | 145.77000000000001 | 84 | 173.54 |
| ZDEF_RETIMER_PRTRST#2 | 162.57 | 156.6 | 103.81 |
| ZDEF_RETIMER_PRTRST#3 | 156.63 | 155.66 | 100.62 |
| ZDEF_RETIMER_R_PERST# | 216.92 | 265.76 | 81.62 |
| ZDEF_RETIMER_R_PRTRST#0 | 896.11 | 968.25 | 92.55 |
| ZDEF_RETIMER_R_PRTRST#1 | 892.56 | 949.74 | 93.98 |
| ZDEF_RETIMER_R_PRTRST#2 | 786.06 | 863.64 | 91.02 |
| ZDEF_RETIMER_R_PRTRST#3 | 724.34 | 788.08 | 91.91 |
| ZDEF_RETIMER_SLAVE_I2C_CLK_R | 3226.31 | 2974.25 | 108.47 |
| ZDEF_RETIMER_SLAVE_I2C_DATA_R | 3159.15 | 2905.74 | 108.72 |
| ZDEF_RITIMER_A_TX_B_RX_DIR | 358.8 | 360.97 | 99.4 |
| ZDEF_RITIMER_DEVICEMODE_DME0 | 380.37 | 352.47 | 107.91 |
| ZDEF_RITIMER_DEVICEMODE_DME1 | 536.33000000000004 | 472.47 | 113.52 |
| ZDEF_RITIMER_DEVICEMODE_DME2 | 519.86 | 520.97 | 99.79 |
| ZDEF_RITIMER_DEVICEMODE_DME3 | 436.75 | 449.47 | 97.17 |
| ZDEF_RITIMER_PCIE_CONFIG_MER0 | 3624.55 | 1821.17 | 199.02 |
| ZDEF_RITIMER_PCIE_CONFIG_MER1 | 3794.78 | 2011.67 | 188.64 |
| ZDEF_RITIMER_PCIE_CONFIG_MER2 | 3353.75 | 1644.66 | 203.92 |
| ZDEF_RITIMER_PCIE_CONFIG_MER0_1_R | 342.94 | 279.89999999999998 | 122.52 |
| ZDEF_RITIMER_PCIE_CONFIG_MER2_R | 97.5 | 108.1 | 90.19 |
| ZDEF_RITIMER_PRTRST_INVERTER | 728.26 | 617.51 | 117.94 |
| ZDEF_RITIMER_SI_CONFIG_DSPFS | 780.95 | 787.63 | 99.15 |
| ZDEF_RITIMER_SI_CONFIG_G2SDE | 625.42999999999995 | 633.14 | 98.78 |
| ZDEF_RITIMER_SI_CONFIG_RXHINT0 | 600.32000000000005 | 584.64 | 102.68 |
| ZDEF_RITIMER_SI_CONFIG_RXHINT1 | 409.35 | 303.97000000000003 | 134.66999999999999 |
| ZDEF_RITIMER_SI_CONFIG_RXHINT2 | 398.82 | 312.47000000000003 | 127.64 |
| ZDEF_RITIMER_SI_CONFIG_TXPRST0 | 693.52 | 639.12 | 108.51 |
| ZDEF_RITIMER_SI_CONFIG_TXPRST1 | 666.21 | 579.36 | 114.99 |
| ZDEF_RITIMER_SI_CONFIG_TXPRST2 | 362.94 | 316.66000000000003 | 114.61 |
| ZDEF_RITIMER_SI_CONFIG_TXPRST3 | 313.20999999999998 | 263.95999999999998 | 118.66 |
| ZDEF_RITIMER_SI_CONFIG_USPFS | 576 | 495.46 | 116.25 |
| ZDEF_SYSTEM_A_PERST# | 751.14 | 854.5 | 87.9 |
| ZDEF_SYSTEM_B_PERST# | 646.53 | 740 | 87.37 |
| ZDEF_SYSTEM_C_PERST# | 321.60000000000002 | 335.3 | 95.92 |
| ZDEF_SYSTEM_D_PERST# | 635.33000000000004 | 789.1 | 80.510000000000005 |
| ZDEF_USB_HUB_PERST# | 363.45 | 208.33 | 174.46 |
